# BASEBOARD_FAB2 (Tioga Pass) — schematic netlist excerpt (pin names and nets, part order shuffled) for the footprints in the layout excerpt that follows; sources: Cadence DE-HDL packaged netlist, KiCad conversion of Wiwynn_Tioga_Pass_MB.brd

C9T9  CAP  10UF 16V 10% X6S  pkg 0805  page 224 : A = VR_FET_SW_P12V_STBY_PVDDQ_GHJ ; B = GND
R9F55  RES  4.75K 1% CHIP  pkg 0402  page 183 : A = P3V3_STBY ; B = FM_UART_ALERT_N
R7E11  RES  4.75K 1% CHIP  pkg 0402  page 95 : A = P3V3 ; B = IRQ_CPU1_VRHOT

(kicad_pcb
	(version 20260206)
	(generator "pcbnew")
	(generator_version "10.0")
	(general
		(thickness 1.6)
		(legacy_teardrops no)
	)
	(paper "A4")
	(title_block
		(title "Wiwynn_Tioga_Pass_MB.brd")
		(comment 1 "Tioga Pass / footprints 3616-3618 of 4770")
	)
	(layers
		(0 "F.Cu" signal "TOP")
		(4 "In1.Cu" signal "L2GND")
		(6 "In2.Cu" signal "L3")
		(8 "In3.Cu" signal "L4GND")
		(10 "In4.Cu" signal "L5")
		(12 "In5.Cu" signal "L6GND")
		(14 "In6.Cu" signal "L7VCC")
		(16 "In7.Cu" signal "L8VCC")
		(18 "In8.Cu" signal "L9GND")
		(20 "In9.Cu" signal "L10")
		(22 "In10.Cu" signal "L11GND")
		(24 "In11.Cu" signal "L12")
		(26 "In12.Cu" signal "L13GND")
		(2 "B.Cu" signal "BOTTOM")
		(9 "F.Adhes" user "F.Adhesive")
		(11 "B.Adhes" user "B.Adhesive")
		(13 "F.Paste" user "Package Geometry/Pastemask Top")
		(15 "B.Paste" user "Package Geometry/Pastemask Bottom")
		(5 "F.SilkS" user "Ref Des/Silkscreen Top")
		(7 "B.SilkS" user "Ref Des/Silkscreen Bottom")
		(1 "F.Mask" user "Board Geometry/Soldermask Top")
		(3 "B.Mask" user "Board Geometry/Soldermask Bottom")
		(17 "Dwgs.User" user "User.Drawings")
		(19 "Cmts.User" user "User.Comments")
		(21 "Eco1.User" user "User.Eco1")
		(23 "Eco2.User" user "User.Eco2")
		(25 "Edge.Cuts" user "Board Geometry/Outline")
		(27 "Margin" user)
		(31 "F.CrtYd" user "Package Geometry/Place Bound Top")
		(29 "B.CrtYd" user "Package Geometry/Place Bound Bottom")
		(35 "F.Fab" user "Ref Des/Assembly Top")
		(33 "B.Fab" user "Ref Des/Assembly Bottom")
	)
	(footprint ""
		(layer "B.Cu")
		(at 381.49022 -79.12354 -90)
		(property "Reference" "R9F55"
			(at 0 0 90)
			(layer "B.SilkS")
			(hide yes)
			(effects
				(font
					(size 1.27 1.27)
				)
				(justify mirror)
			)
		)
		(property "Value" ""
			(at 0 0 90)
			(layer "B.Fab")
			(effects
				(font
					(size 1.27 1.27)
				)
				(justify mirror)
			)
		)
		(duplicate_pad_numbers_are_jumpers no)
		(fp_poly
			(pts
				(xy 0.2794 -0.1016) (xy -0.2794 -0.1016) (xy -0.2794 0.9906) (xy 0.2794 0.9906)
			)
			(stroke
				(width 0)
				(type default)
			)
			(fill no)
			(layer "B.CrtYd")
		)
		(fp_line
			(start -0.2794 0.9906)
			(end -0.2794 -0.1016)
			(stroke
				(width 0.1)
				(type default)
			)
			(layer "B.Fab")
		)
		(fp_line
			(start 0.2794 0.9906)
			(end -0.2794 0.9906)
			(stroke
				(width 0.1)
				(type default)
			)
			(layer "B.Fab")
		)
		(fp_line
			(start -0.2794 -0.1016)
			(end 0.2794 -0.1016)
			(stroke
				(width 0.1)
				(type default)
			)
			(layer "B.Fab")
		)
		(fp_line
			(start 0.2794 -0.1016)
			(end 0.2794 0.9906)
			(stroke
				(width 0.1)
				(type default)
			)
			(layer "B.Fab")
		)
		(pad "1" smd rect
			(at 0 0 90)
			(size 0.508 0.508)
			(layers "B.Cu" "B.Mask" "B.Paste")
			(net "P3V3_STBY")
		)
		(pad "2" smd rect
			(at 0 0.889 90)
			(size 0.508 0.508)
			(layers "B.Cu" "B.Mask" "B.Paste")
			(net "FM_UART_ALERT_N")
		)
		(zone
			(layer "B.Cu")
			(hatch none 0.5)
			(connect_pads
				(clearance 0)
			)
			(min_thickness 0.25)
			(keepout
				(tracks not_allowed)
				(vias allowed)
				(pads allowed)
				(copperpour not_allowed)
				(footprints allowed)
			)
			(placement
				(enabled no)
				(sheetname "")
			)
			(fill
				(thermal_gap 0.5)
				(thermal_bridge_width 0.5)
				(island_removal_mode 0)
			)
			(polygon
				(pts
					(xy 380.85522 -78.86954) (xy 380.85522 -79.37754) (xy 381.23622 -79.37754) (xy 381.23622 -78.86954)
				)
			)
		)
		(zone
			(layer "B.Cu")
			(hatch none 0.5)
			(connect_pads
				(clearance 0)
			)
			(min_thickness 0.25)
			(keepout
				(tracks allowed)
				(vias not_allowed)
				(pads allowed)
				(copperpour not_allowed)
				(footprints allowed)
			)
			(placement
				(enabled no)
				(sheetname "")
			)
			(fill
				(thermal_gap 0.5)
				(thermal_bridge_width 0.5)
				(island_removal_mode 0)
			)
			(polygon
				(pts
					(xy 381.23622 -78.86954) (xy 381.23622 -79.37754) (xy 380.85522 -79.37754) (xy 380.85522 -78.86954)
				)
			)
		)
	)
	(footprint ""
		(layer "B.Cu")
		(at 382.3335 -44.958 90)
		(property "Reference" "R7E11"
			(at 0 0 90)
			(layer "B.SilkS")
			(hide yes)
			(effects
				(font
					(size 1.27 1.27)
				)
				(justify mirror)
			)
		)
		(property "Value" ""
			(at 0 0 90)
			(layer "B.Fab")
			(effects
				(font
					(size 1.27 1.27)
				)
				(justify mirror)
			)
		)
		(duplicate_pad_numbers_are_jumpers no)
		(fp_poly
			(pts
				(xy 0.2794 -0.1016) (xy -0.2794 -0.1016) (xy -0.2794 0.9906) (xy 0.2794 0.9906)
			)
			(stroke
				(width 0)
				(type default)
			)
			(fill no)
			(layer "B.CrtYd")
		)
		(fp_line
			(start 0.2794 -0.1016)
			(end 0.2794 0.9906)
			(stroke
				(width 0.1)
				(type default)
			)
			(layer "B.Fab")
		)
		(fp_line
			(start -0.2794 -0.1016)
			(end 0.2794 -0.1016)
			(stroke
				(width 0.1)
				(type default)
			)
			(layer "B.Fab")
		)
		(fp_line
			(start 0.2794 0.9906)
			(end -0.2794 0.9906)
			(stroke
				(width 0.1)
				(type default)
			)
			(layer "B.Fab")
		)
		(fp_line
			(start -0.2794 0.9906)
			(end -0.2794 -0.1016)
			(stroke
				(width 0.1)
				(type default)
			)
			(layer "B.Fab")
		)
		(pad "1" smd rect
			(at 0 0 270)
			(size 0.508 0.508)
			(layers "B.Cu" "B.Mask" "B.Paste")
			(net "P3V3")
		)
		(pad "2" smd rect
			(at 0 0.889 270)
			(size 0.508 0.508)
			(layers "B.Cu" "B.Mask" "B.Paste")
			(net "IRQ_CPU1_VRHOT")
		)
		(zone
			(layer "B.Cu")
			(hatch none 0.5)
			(connect_pads
				(clearance 0)
			)
			(min_thickness 0.25)
			(keepout
				(tracks allowed)
				(vias not_allowed)
				(pads allowed)
				(copperpour not_allowed)
				(footprints allowed)
			)
			(placement
				(enabled no)
				(sheetname "")
			)
			(fill
				(thermal_gap 0.5)
				(thermal_bridge_width 0.5)
				(island_removal_mode 0)
			)
			(polygon
				(pts
					(xy 382.5875 -45.212) (xy 382.5875 -44.704) (xy 382.9685 -44.704) (xy 382.9685 -45.212)
				)
			)
		)
		(zone
			(layer "B.Cu")
			(hatch none 0.5)
			(connect_pads
				(clearance 0)
			)
			(min_thickness 0.25)
			(keepout
				(tracks not_allowed)
				(vias allowed)
				(pads allowed)
				(copperpour not_allowed)
				(footprints allowed)
			)
			(placement
				(enabled no)
				(sheetname "")
			)
			(fill
				(thermal_gap 0.5)
				(thermal_bridge_width 0.5)
				(island_removal_mode 0)
			)
			(polygon
				(pts
					(xy 382.9685 -45.212) (xy 382.9685 -44.704) (xy 382.5875 -44.704) (xy 382.5875 -45.212)
				)
			)
		)
	)
	(footprint ""
		(layer "B.Cu")
		(at 3.920998 -16.934942 90)
		(property "Reference" "C9T9"
			(at 0 0 90)
			(layer "B.SilkS")
			(hide yes)
			(effects
				(font
					(size 1.27 1.27)
				)
				(justify mirror)
			)
		)
		(property "Value" ""
			(at 0 0 90)
			(layer "B.Fab")
			(effects
				(font
					(size 1.27 1.27)
				)
				(justify mirror)
			)
		)
		(duplicate_pad_numbers_are_jumpers no)
		(fp_rect
			(start -0.7239 -0.2159)
			(end 0.7239 1.9939)
			(stroke
				(width 0)
				(type default)
			)
			(fill no)
			(layer "B.CrtYd")
		)
		(fp_line
			(start 0.7239 -0.2159)
			(end 0.7239 1.9939)
			(stroke
				(width 0.1)
				(type default)
			)
			(layer "B.Fab")
		)
		(fp_line
			(start -0.7239 -0.2159)
			(end 0.7239 -0.2159)
			(stroke
				(width 0.1)
				(type default)
			)
			(layer "B.Fab")
		)
		(fp_line
			(start 0.7239 1.9939)
			(end -0.7239 1.9939)
			(stroke
				(width 0.1)
				(type default)
			)
			(layer "B.Fab")
		)
		(fp_line
			(start -0.7239 1.9939)
			(end -0.7239 -0.2159)
			(stroke
				(width 0.1)
				(type default)
			)
			(layer "B.Fab")
		)
		(pad "1" smd rect
			(at 0 0 270)
			(size 1.27 1.016)
			(layers "B.Cu" "B.Mask" "B.Paste")
			(net "VR_FET_SW_P12V_STBY_PVDDQ_GHJ")
		)
		(pad "2" smd rect
			(at 0 1.778 270)
			(size 1.27 1.016)
			(layers "B.Cu" "B.Mask" "B.Paste")
			(net "GND")
		)
		(zone
			(layer "B.Cu")
			(hatch none 0.5)
			(connect_pads
				(clearance 0)
			)
			(min_thickness 0.25)
			(keepout
				(tracks not_allowed)
				(vias allowed)
				(pads allowed)
				(copperpour not_allowed)
				(footprints allowed)
			)
			(placement
				(enabled no)
				(sheetname "")
			)
			(fill
				(thermal_gap 0.5)
				(thermal_bridge_width 0.5)
				(island_removal_mode 0)
			)
			(polygon
				(pts
					(xy 4.428998 -16.299942) (xy 5.190998 -16.299942) (xy 5.190998 -17.569942) (xy 4.428998 -17.569942)
				)
			)
		)
	)
)
